(kicad_pcb
	(version 20260206)
	(generator "pcbnew")
	(generator_version "10.0")
	(general
		(thickness 1.6)
		(legacy_teardrops no)
	)
	(paper "A4")
	(title_block
		(title "Bryce Canyon_SCC_16316-1_OCP.brd")
		(comment 1 "Bryce Canyon / footprints 242-248 of 1561")
	)
	(layers
		(0 "F.Cu" signal "TOP")
		(4 "In1.Cu" signal "L2GND")
		(6 "In2.Cu" signal "L3")
		(8 "In3.Cu" signal "L4VCC")
		(10 "In4.Cu" signal "L5VCC")
		(12 "In5.Cu" signal "L6")
		(14 "In6.Cu" signal "L7GND")
		(2 "B.Cu" signal "BOTTOM")
		(9 "F.Adhes" user "F.Adhesive")
		(11 "B.Adhes" user "B.Adhesive")
		(13 "F.Paste" user "Package Geometry/Pastemask Top")
		(15 "B.Paste" user "Package Geometry/Pastemask Bottom")
		(5 "F.SilkS" user "Ref Des/Silkscreen Top")
		(7 "B.SilkS" user "Ref Des/Silkscreen Bottom")
		(1 "F.Mask" user "Board Geometry/Soldermask Top")
		(3 "B.Mask" user "Board Geometry/Soldermask Bottom")
		(17 "Dwgs.User" user "User.Drawings")
		(19 "Cmts.User" user "User.Comments")
		(21 "Eco1.User" user "User.Eco1")
		(23 "Eco2.User" user "User.Eco2")
		(25 "Edge.Cuts" user "Board Geometry/Outline")
		(27 "Margin" user)
		(31 "F.CrtYd" user "Package Geometry/Place Bound Top")
		(29 "B.CrtYd" user "Package Geometry/Place Bound Bottom")
		(35 "F.Fab" user "Ref Des/Assembly Top")
		(33 "B.Fab" user "Ref Des/Assembly Bottom")
	)
	(footprint ""
		(layer "F.Cu")
		(at 63.34125 -77.487018 180)
		(property "Reference" "U38"
			(at 0 0 180)
			(layer "F.SilkS")
			(hide yes)
			(effects
				(font
					(size 1.27 1.27)
				)
			)
		)
		(property "Value" "PCA9306DCTR-GP"
			(at 0 -11.6332 180)
			(unlocked yes)
			(layer "F.Fab")
			(hide yes)
			(effects
				(font
					(size 1.016 1.016)
					(thickness 0.1524)
				)
			)
		)
		(property "Device Type" "SSOIC8H52"
			(at 0 -13.1572 180)
			(unlocked yes)
			(layer "F.Fab")
			(hide yes)
			(effects
				(font
					(size 1.016 1.016)
					(thickness 0.1524)
				)
			)
		)
		(duplicate_pad_numbers_are_jumpers no)
		(fp_line
			(start 1.0668 0.5842)
			(end -1.524 0.5842)
			(stroke
				(width 0.1524)
				(type default)
			)
			(layer "F.SilkS")
		)
		(fp_line
			(start 1.0668 -0.5842)
			(end 1.0668 0.5842)
			(stroke
				(width 0.1524)
				(type default)
			)
			(layer "F.SilkS")
		)
		(fp_line
			(start -1.397 0)
			(end -1.7018 0.3048)
			(stroke
				(width 0.1524)
				(type default)
			)
			(layer "F.SilkS")
		)
		(fp_line
			(start -1.397 0)
			(end -1.7018 -0.3048)
			(stroke
				(width 0.1524)
				(type default)
			)
			(layer "F.SilkS")
		)
		(fp_line
			(start -1.524 0.5842)
			(end -1.524 2.286)
			(stroke
				(width 0.508)
				(type default)
			)
			(layer "F.SilkS")
		)
		(fp_line
			(start -1.7018 -0.5842)
			(end 1.0668 -0.5842)
			(stroke
				(width 0.1524)
				(type default)
			)
			(layer "F.SilkS")
		)
		(fp_line
			(start -1.7018 -0.5842)
			(end -1.7018 2.286)
			(stroke
				(width 0.1524)
				(type default)
			)
			(layer "F.SilkS")
		)
		(fp_poly
			(pts
				(xy -1.1684 -0.5842) (xy 1.0668 -0.5842) (xy 1.0668 0.5842) (xy -1.1684 0.5842)
			)
			(stroke
				(width 0)
				(type default)
			)
			(fill yes)
			(layer "F.SilkS")
		)
		(fp_poly
			(pts
				(xy -1.778 2.54) (xy 1.778 2.54) (xy 1.778 -2.54) (xy -1.778 -2.54)
			)
			(stroke
				(width 0)
				(type default)
			)
			(fill no)
			(layer "F.CrtYd")
		)
		(fp_poly
			(pts
				(xy -1.778 -2.54) (xy 1.778 -2.54) (xy 1.778 2.54) (xy -1.778 2.54)
			)
			(stroke
				(width 0)
				(type default)
			)
			(fill no)
			(layer "F.Fab")
		)
		(pad "1" smd rect
			(at -0.97536 1.6256 180)
			(size 0.3556 1.524)
			(layers "F.Cu" "F.Mask" "F.Paste")
			(net "GND")
		)
		(pad "2" smd rect
			(at -0.32512 1.6256 180)
			(size 0.3556 1.524)
			(layers "F.Cu" "F.Mask" "F.Paste")
			(net "P1V8_E")
		)
		(pad "3" smd rect
			(at 0.32512 1.6256 180)
			(size 0.3556 1.524)
			(layers "F.Cu" "F.Mask" "F.Paste")
			(net "I2C_DRIVE_INS_SCL5_LS")
		)
		(pad "4" smd rect
			(at 0.97536 1.6256 180)
			(size 0.3556 1.524)
			(layers "F.Cu" "F.Mask" "F.Paste")
			(net "I2C_DRIVE_INS_SDA5_LS")
		)
		(pad "5" smd rect
			(at 0.97536 -1.6256 180)
			(size 0.3556 1.524)
			(layers "F.Cu" "F.Mask" "F.Paste")
			(net "I2C_DRIVE_INS_SDA5")
		)
		(pad "6" smd rect
			(at 0.32512 -1.6256 180)
			(size 0.3556 1.524)
			(layers "F.Cu" "F.Mask" "F.Paste")
			(net "I2C_DRIVE_INS_SCL5")
		)
		(pad "7" smd rect
			(at -0.32512 -1.6256 180)
			(size 0.3556 1.524)
			(layers "F.Cu" "F.Mask" "F.Paste")
			(net "VREF5")
		)
		(pad "8" smd rect
			(at -0.97536 -1.6256 180)
			(size 0.3556 1.524)
			(layers "F.Cu" "F.Mask" "F.Paste")
			(net "LS_EN_U38")
		)
	)
	(footprint ""
		(layer "F.Cu")
		(at 55.7276 -72.5678 180)
		(property "Reference" "R421"
			(at 0 0 180)
			(layer "F.SilkS")
			(hide yes)
			(effects
				(font
					(size 1.27 1.27)
				)
			)
		)
		(property "Value" "1KR2F-3-GP"
			(at 0.064008 -3.993896 180)
			(unlocked yes)
			(layer "F.Fab")
			(hide yes)
			(effects
				(font
					(size 1.016 1.016)
					(thickness 0.1524)
				)
			)
		)
		(property "Device Type" "R402H16"
			(at 0.064008 -5.517896 180)
			(unlocked yes)
			(layer "F.Fab")
			(hide yes)
			(effects
				(font
					(size 1.016 1.016)
					(thickness 0.1524)
				)
			)
		)
		(duplicate_pad_numbers_are_jumpers no)
		(fp_line
			(start 0.508 -0.9398)
			(end -0.508 -0.9398)
			(stroke
				(width 0.1524)
				(type default)
			)
			(layer "F.SilkS")
		)
		(fp_line
			(start -0.508 -0.9398)
			(end -0.508 0.9398)
			(stroke
				(width 0.1524)
				(type default)
			)
			(layer "F.SilkS")
		)
		(fp_rect
			(start -0.508 0.9398)
			(end 0.508 -0.9398)
			(stroke
				(width 0)
				(type default)
			)
			(fill no)
			(layer "F.CrtYd")
		)
		(fp_rect
			(start -0.508 0.9398)
			(end 0.508 -0.9398)
			(stroke
				(width 0)
				(type default)
			)
			(fill no)
			(layer "F.Fab")
		)
		(pad "1" smd custom
			(at 0 -0.4445 180)
			(size 0.1397 0.1397)
			(layers "F.Cu" "F.Mask" "F.Paste")
			(net "P3V3")
			(options
				(clearance outline)
				(anchor circle)
			)
			(primitives
				(gr_poly
					(pts
						(arc
							(start -0.1778 -0.2794)
							(mid -0.249642 -0.249642)
							(end -0.2794 -0.1778)
						)
						(arc
							(start -0.2794 0.1778)
							(mid -0.249642 0.249642)
							(end -0.1778 0.2794)
						)
						(arc
							(start 0.1778 0.2794)
							(mid 0.249642 0.249642)
							(end 0.2794 0.1778)
						)
						(arc
							(start 0.2794 -0.1778)
							(mid 0.249642 -0.249642)
							(end 0.1778 -0.2794)
						)
					)
					(width 0)
					(fill yes)
				)
			)
		)
		(pad "2" smd custom
			(at 0 0.4445 180)
			(size 0.1397 0.1397)
			(layers "F.Cu" "F.Mask" "F.Paste")
			(net "I2C_DRIVE_PWR_SDA4")
			(options
				(clearance outline)
				(anchor circle)
			)
			(primitives
				(gr_poly
					(pts
						(arc
							(start -0.1778 -0.2794)
							(mid -0.249642 -0.249642)
							(end -0.2794 -0.1778)
						)
						(arc
							(start -0.2794 0.1778)
							(mid -0.249642 0.249642)
							(end -0.1778 0.2794)
						)
						(arc
							(start 0.1778 0.2794)
							(mid 0.249642 0.249642)
							(end 0.2794 0.1778)
						)
						(arc
							(start 0.2794 -0.1778)
							(mid 0.249642 -0.249642)
							(end 0.1778 -0.2794)
						)
					)
					(width 0)
					(fill yes)
				)
			)
		)
	)
	(footprint ""
		(layer "F.Cu")
		(at 22.8092 -47.0154 180)
		(property "Reference" "R551"
			(at 0 0 180)
			(layer "F.SilkS")
			(hide yes)
			(effects
				(font
					(size 1.27 1.27)
				)
			)
		)
		(property "Value" "49K9R2F-L-GP"
			(at 0.064008 -3.993896 180)
			(unlocked yes)
			(layer "F.Fab")
			(hide yes)
			(effects
				(font
					(size 1.016 1.016)
					(thickness 0.1524)
				)
			)
		)
		(property "Device Type" "R402H16"
			(at 0.064008 -5.517896 180)
			(unlocked yes)
			(layer "F.Fab")
			(hide yes)
			(effects
				(font
					(size 1.016 1.016)
					(thickness 0.1524)
				)
			)
		)
		(duplicate_pad_numbers_are_jumpers no)
		(fp_line
			(start 0.508 -0.9398)
			(end -0.508 -0.9398)
			(stroke
				(width 0.1524)
				(type default)
			)
			(layer "F.SilkS")
		)
		(fp_line
			(start -0.508 -0.9398)
			(end -0.508 0.9398)
			(stroke
				(width 0.1524)
				(type default)
			)
			(layer "F.SilkS")
		)
		(fp_rect
			(start -0.508 0.9398)
			(end 0.508 -0.9398)
			(stroke
				(width 0)
				(type default)
			)
			(fill no)
			(layer "F.CrtYd")
		)
		(fp_rect
			(start -0.508 0.9398)
			(end 0.508 -0.9398)
			(stroke
				(width 0)
				(type default)
			)
			(fill no)
			(layer "F.Fab")
		)
		(pad "1" smd custom
			(at 0 -0.4445 180)
			(size 0.1397 0.1397)
			(layers "F.Cu" "F.Mask" "F.Paste")
			(net "P12V_MAIN")
			(options
				(clearance outline)
				(anchor circle)
			)
			(primitives
				(gr_poly
					(pts
						(arc
							(start -0.1778 -0.2794)
							(mid -0.249642 -0.249642)
							(end -0.2794 -0.1778)
						)
						(arc
							(start -0.2794 0.1778)
							(mid -0.249642 0.249642)
							(end -0.1778 0.2794)
						)
						(arc
							(start 0.1778 0.2794)
							(mid 0.249642 0.249642)
							(end 0.2794 0.1778)
						)
						(arc
							(start 0.2794 -0.1778)
							(mid 0.249642 -0.249642)
							(end 0.1778 -0.2794)
						)
					)
					(width 0)
					(fill yes)
				)
			)
		)
		(pad "2" smd custom
			(at 0 0.4445 180)
			(size 0.1397 0.1397)
			(layers "F.Cu" "F.Mask" "F.Paste")
			(net "MB0_CM_OV_R")
			(options
				(clearance outline)
				(anchor circle)
			)
			(primitives
				(gr_poly
					(pts
						(arc
							(start -0.1778 -0.2794)
							(mid -0.249642 -0.249642)
							(end -0.2794 -0.1778)
						)
						(arc
							(start -0.2794 0.1778)
							(mid -0.249642 0.249642)
							(end -0.1778 0.2794)
						)
						(arc
							(start 0.1778 0.2794)
							(mid 0.249642 0.249642)
							(end 0.2794 0.1778)
						)
						(arc
							(start 0.2794 -0.1778)
							(mid 0.249642 -0.249642)
							(end 0.1778 -0.2794)
						)
					)
					(width 0)
					(fill yes)
				)
			)
		)
	)
	(footprint ""
		(layer "F.Cu")
		(at 6.6294 -94.831408 180)
		(property "Reference" "C548"
			(at 0 0 180)
			(layer "F.SilkS")
			(hide yes)
			(effects
				(font
					(size 1.27 1.27)
				)
			)
		)
		(property "Value" "SCD1U16V2KX-3GP"
			(at 1.1811 -2.7051 180)
			(unlocked yes)
			(layer "F.Fab")
			(hide yes)
			(effects
				(font
					(size 1.016 1.016)
					(thickness 0.1524)
				)
			)
		)
		(property "Device Type" "C402H22"
			(at 1.1811 -4.2291 180)
			(unlocked yes)
			(layer "F.Fab")
			(hide yes)
			(effects
				(font
					(size 1.016 1.016)
					(thickness 0.1524)
				)
			)
		)
		(duplicate_pad_numbers_are_jumpers no)
		(fp_rect
			(start -0.4318 0.9525)
			(end 0.4318 -0.9525)
			(stroke
				(width 0)
				(type default)
			)
			(fill no)
			(layer "F.CrtYd")
		)
		(fp_rect
			(start -0.4318 0.9525)
			(end 0.4318 -0.9525)
			(stroke
				(width 0)
				(type default)
			)
			(fill no)
			(layer "F.Fab")
		)
		(pad "1" smd custom
			(at 0 -0.4445 180)
			(size 0.1524 0.1524)
			(layers "F.Cu" "F.Mask" "F.Paste")
			(net "VREF2")
			(options
				(clearance outline)
				(anchor circle)
			)
			(primitives
				(gr_poly
					(pts
						(arc
							(start 0.3048 -0.2032)
							(mid 0.275042 -0.275042)
							(end 0.2032 -0.3048)
						)
						(arc
							(start -0.2032 -0.3048)
							(mid -0.275042 -0.275042)
							(end -0.3048 -0.2032)
						)
						(arc
							(start -0.3048 0.2032)
							(mid -0.275042 0.275042)
							(end -0.2032 0.3048)
						)
						(arc
							(start 0.2032 0.3048)
							(mid 0.275042 0.275042)
							(end 0.3048 0.2032)
						)
					)
					(width 0)
					(fill yes)
				)
			)
		)
		(pad "2" smd custom
			(at 0 0.4445 180)
			(size 0.1524 0.1524)
			(layers "F.Cu" "F.Mask" "F.Paste")
			(net "GND")
			(options
				(clearance outline)
				(anchor circle)
			)
			(primitives
				(gr_poly
					(pts
						(arc
							(start 0.3048 -0.2032)
							(mid 0.275042 -0.275042)
							(end 0.2032 -0.3048)
						)
						(arc
							(start -0.2032 -0.3048)
							(mid -0.275042 -0.275042)
							(end -0.3048 -0.2032)
						)
						(arc
							(start -0.3048 0.2032)
							(mid -0.275042 0.275042)
							(end -0.2032 0.3048)
						)
						(arc
							(start 0.2032 0.3048)
							(mid 0.275042 0.275042)
							(end 0.3048 0.2032)
						)
					)
					(width 0)
					(fill yes)
				)
			)
		)
	)
	(footprint ""
		(layer "F.Cu")
		(at 8.20547 -89.054178)
		(property "Reference" "U36"
			(at 0 0 0)
			(layer "F.SilkS")
			(hide yes)
			(effects
				(font
					(size 1.27 1.27)
				)
			)
		)
		(property "Value" "PCA9306DCTR-GP"
			(at 0 -11.6332 0)
			(unlocked yes)
			(layer "F.Fab")
			(hide yes)
			(effects
				(font
					(size 1.016 1.016)
					(thickness 0.1524)
				)
			)
		)
		(property "Device Type" "SSOIC8H52"
			(at 0 -13.1572 0)
			(unlocked yes)
			(layer "F.Fab")
			(hide yes)
			(effects
				(font
					(size 1.016 1.016)
					(thickness 0.1524)
				)
			)
		)
		(duplicate_pad_numbers_are_jumpers no)
		(fp_line
			(start -1.7018 -0.5842)
			(end -1.7018 2.286)
			(stroke
				(width 0.1524)
				(type default)
			)
			(layer "F.SilkS")
		)
		(fp_line
			(start -1.7018 -0.5842)
			(end 1.0668 -0.5842)
			(stroke
				(width 0.1524)
				(type default)
			)
			(layer "F.SilkS")
		)
		(fp_line
			(start -1.524 0.5842)
			(end -1.524 2.286)
			(stroke
				(width 0.508)
				(type default)
			)
			(layer "F.SilkS")
		)
		(fp_line
			(start -1.397 0)
			(end -1.7018 -0.3048)
			(stroke
				(width 0.1524)
				(type default)
			)
			(layer "F.SilkS")
		)
		(fp_line
			(start -1.397 0)
			(end -1.7018 0.3048)
			(stroke
				(width 0.1524)
				(type default)
			)
			(layer "F.SilkS")
		)
		(fp_line
			(start 1.0668 -0.5842)
			(end 1.0668 0.5842)
			(stroke
				(width 0.1524)
				(type default)
			)
			(layer "F.SilkS")
		)
		(fp_line
			(start 1.0668 0.5842)
			(end -1.524 0.5842)
			(stroke
				(width 0.1524)
				(type default)
			)
			(layer "F.SilkS")
		)
		(fp_poly
			(pts
				(xy -1.1684 -0.5842) (xy 1.0668 -0.5842) (xy 1.0668 0.5842) (xy -1.1684 0.5842)
			)
			(stroke
				(width 0)
				(type default)
			)
			(fill yes)
			(layer "F.SilkS")
		)
		(fp_poly
			(pts
				(xy -1.778 2.54) (xy 1.778 2.54) (xy 1.778 -2.54) (xy -1.778 -2.54)
			)
			(stroke
				(width 0)
				(type default)
			)
			(fill no)
			(layer "F.CrtYd")
		)
		(fp_poly
			(pts
				(xy -1.778 -2.54) (xy 1.778 -2.54) (xy 1.778 2.54) (xy -1.778 2.54)
			)
			(stroke
				(width 0)
				(type default)
			)
			(fill no)
			(layer "F.Fab")
		)
		(pad "1" smd rect
			(at -0.97536 1.6256)
			(size 0.3556 1.524)
			(layers "F.Cu" "F.Mask" "F.Paste")
			(net "GND")
		)
		(pad "2" smd rect
			(at -0.32512 1.6256)
			(size 0.3556 1.524)
			(layers "F.Cu" "F.Mask" "F.Paste")
			(net "P1V8_E")
		)
		(pad "3" smd rect
			(at 0.32512 1.6256)
			(size 0.3556 1.524)
			(layers "F.Cu" "F.Mask" "F.Paste")
			(net "I2C_SCC_SCL2_LS")
		)
		(pad "4" smd rect
			(at 0.97536 1.6256)
			(size 0.3556 1.524)
			(layers "F.Cu" "F.Mask" "F.Paste")
			(net "I2C_SCC_SDA2_LS")
		)
		(pad "5" smd rect
			(at 0.97536 -1.6256)
			(size 0.3556 1.524)
			(layers "F.Cu" "F.Mask" "F.Paste")
			(net "I2C_SCC_SDA2")
		)
		(pad "6" smd rect
			(at 0.32512 -1.6256)
			(size 0.3556 1.524)
			(layers "F.Cu" "F.Mask" "F.Paste")
			(net "I2C_SCC_SCL2")
		)
		(pad "7" smd rect
			(at -0.32512 -1.6256)
			(size 0.3556 1.524)
			(layers "F.Cu" "F.Mask" "F.Paste")
			(net "VREF2")
		)
		(pad "8" smd rect
			(at -0.97536 -1.6256)
			(size 0.3556 1.524)
			(layers "F.Cu" "F.Mask" "F.Paste")
			(net "LS_EN_U36")
		)
	)
	(footprint ""
		(layer "F.Cu")
		(at 147.317206 -51.039268 102)
		(property "Reference" "C341"
			(at 0 0 102)
			(layer "F.SilkS")
			(hide yes)
			(effects
				(font
					(size 1.27 1.27)
				)
			)
		)
		(property "Value" "SCD01U16V1KX-GP"
			(at -2.831995 -1.740026 102)
			(unlocked yes)
			(layer "F.Fab")
			(hide yes)
			(effects
				(font
					(size 1.016 1.016)
					(thickness 0.1524)
				)
			)
		)
		(property "Device Type" "C0201H13"
			(at -2.831872 -3.264029 102)
			(unlocked yes)
			(layer "F.Fab")
			(hide yes)
			(effects
				(font
					(size 1.016 1.016)
					(thickness 0.1524)
				)
			)
		)
		(duplicate_pad_numbers_are_jumpers no)
		(fp_poly
			(pts
				(xy -0.279454 -0.647706) (xy 0.279346 -0.647706) (xy 0.279346 0.647694) (xy -0.279454 0.647694)
			)
			(stroke
				(width 0)
				(type default)
			)
			(fill no)
			(layer "F.CrtYd")
		)
		(fp_poly
			(pts
				(xy -0.279454 -0.647706) (xy 0.279346 -0.647706) (xy 0.279346 0.647694) (xy -0.279454 0.647694)
			)
			(stroke
				(width 0)
				(type default)
			)
			(fill no)
			(layer "F.Fab")
		)
		(pad "1" smd custom
			(at -0.000001 -0.2794 102)
			(size 0.0762 0.0762)
			(layers "F.Cu" "F.Mask" "F.Paste")
			(net "PHY_SCC_TO_IOC_46_DP")
			(options
				(clearance outline)
				(anchor circle)
			)
			(primitives
				(gr_poly
					(pts
						(arc
							(start 0.1524 -0.127)
							(mid 0.137521 -0.162921)
							(end 0.1016 -0.1778)
						)
						(arc
							(start -0.1016 -0.1778)
							(mid -0.137521 -0.162921)
							(end -0.1524 -0.127)
						)
						(arc
							(start -0.1524 0.127)
							(mid -0.137521 0.162921)
							(end -0.1016 0.1778)
						)
						(arc
							(start 0.1016 0.1778)
							(mid 0.137521 0.162921)
							(end 0.1524 0.127)
						)
					)
					(width 0)
					(fill yes)
				)
			)
		)
		(pad "2" smd custom
			(at 0.000001 0.2794 102)
			(size 0.0762 0.0762)
			(layers "F.Cu" "F.Mask" "F.Paste")
			(net "PHY_SCC_TO_IOC_C_46_DP")
			(options
				(clearance outline)
				(anchor circle)
			)
			(primitives
				(gr_poly
					(pts
						(arc
							(start 0.1524 -0.127)
							(mid 0.137521 -0.162921)
							(end 0.1016 -0.1778)
						)
						(arc
							(start -0.1016 -0.1778)
							(mid -0.137521 -0.162921)
							(end -0.1524 -0.127)
						)
						(arc
							(start -0.1524 0.127)
							(mid -0.137521 0.162921)
							(end -0.1016 0.1778)
						)
						(arc
							(start 0.1016 0.1778)
							(mid 0.137521 0.162921)
							(end 0.1524 0.127)
						)
					)
					(width 0)
					(fill yes)
				)
			)
		)
	)
	(footprint ""
		(layer "F.Cu")
		(at 136.181592 -77.272134 90)
		(property "Reference" "C680"
			(at 0 0 90)
			(layer "F.SilkS")
			(hide yes)
			(effects
				(font
					(size 1.27 1.27)
				)
			)
		)
		(property "Value" "SCD01U16V1KX-GP"
			(at -2.8321 -1.7399 90)
			(unlocked yes)
			(layer "F.Fab")
			(hide yes)
			(effects
				(font
					(size 1.016 1.016)
					(thickness 0.1524)
				)
			)
		)
		(property "Device Type" "C0201H13"
			(at -2.8321 -3.2639 90)
			(unlocked yes)
			(layer "F.Fab")
			(hide yes)
			(effects
				(font
					(size 1.016 1.016)
					(thickness 0.1524)
				)
			)
		)
		(duplicate_pad_numbers_are_jumpers no)
		(fp_rect
			(start -0.2794 0.6477)
			(end 0.2794 -0.6477)
			(stroke
				(width 0)
				(type default)
			)
			(fill no)
			(layer "F.CrtYd")
		)
		(fp_rect
			(start -0.2794 0.6477)
			(end 0.2794 -0.6477)
			(stroke
				(width 0)
				(type default)
			)
			(fill no)
			(layer "F.Fab")
		)
		(pad "1" smd custom
			(at 0 -0.2794 90)
			(size 0.0762 0.0762)
			(layers "F.Cu" "F.Mask" "F.Paste")
			(net "PHY_EXP_TO_CONN_C_9_DP")
			(options
				(clearance outline)
				(anchor circle)
			)
			(primitives
				(gr_poly
					(pts
						(arc
							(start 0.1524 -0.127)
							(mid 0.137521 -0.162921)
							(end 0.1016 -0.1778)
						)
						(arc
							(start -0.1016 -0.1778)
							(mid -0.137521 -0.162921)
							(end -0.1524 -0.127)
						)
						(arc
							(start -0.1524 0.127)
							(mid -0.137521 0.162921)
							(end -0.1016 0.1778)
						)
						(arc
							(start 0.1016 0.1778)
							(mid 0.137521 0.162921)
							(end 0.1524 0.127)
						)
					)
					(width 0)
					(fill yes)
				)
			)
		)
		(pad "2" smd custom
			(at 0 0.2794 90)
			(size 0.0762 0.0762)
			(layers "F.Cu" "F.Mask" "F.Paste")
			(net "PHY_EXP_TO_CONN_9_DP")
			(options
				(clearance outline)
				(anchor circle)
			)
			(primitives
				(gr_poly
					(pts
						(arc
							(start 0.1524 -0.127)
							(mid 0.137521 -0.162921)
							(end 0.1016 -0.1778)
						)
						(arc
							(start -0.1016 -0.1778)
							(mid -0.137521 -0.162921)
							(end -0.1524 -0.127)
						)
						(arc
							(start -0.1524 0.127)
							(mid -0.137521 0.162921)
							(end -0.1016 0.1778)
						)
						(arc
							(start 0.1016 0.1778)
							(mid 0.137521 0.162921)
							(end 0.1524 0.127)
						)
					)
					(width 0)
					(fill yes)
				)
			)
		)
	)
)
